(kicad_pcb
	(version 20241229)
	(generator "pcbnew")
	(generator_version "9.0")
	(general
		(thickness 1.61)
		(legacy_teardrops no)
	)
	(paper "A3")
	(title_block
		(title "RDIMM DDR5 Tester")
		(date "2026-05-21")
		(rev "2.2.0")
		(company "Antmicro")
		(comment 9 "footprints 661-663 of 796")
	)
	(layers
		(0 "F.Cu" signal)
		(4 "In1.Cu" power)
		(6 "In2.Cu" mixed)
		(8 "In3.Cu" power)
		(10 "In4.Cu" mixed)
		(12 "In5.Cu" power)
		(14 "In6.Cu" mixed)
		(16 "In7.Cu" power)
		(18 "In8.Cu" power)
		(20 "In9.Cu" mixed)
		(22 "In10.Cu" power)
		(2 "B.Cu" signal)
		(9 "F.Adhes" user "F.Adhesive")
		(11 "B.Adhes" user "B.Adhesive")
		(13 "F.Paste" user)
		(15 "B.Paste" user)
		(5 "F.SilkS" user "F.Silkscreen")
		(7 "B.SilkS" user "B.Silkscreen")
		(1 "F.Mask" user)
		(3 "B.Mask" user)
		(17 "Dwgs.User" user "User.Drawings")
		(19 "Cmts.User" user "User.Comments")
		(21 "Eco1.User" user "User.Eco1")
		(23 "Eco2.User" user "User.Eco2")
		(25 "Edge.Cuts" user)
		(27 "Margin" user)
		(31 "F.CrtYd" user "F.Courtyard")
		(29 "B.CrtYd" user "B.Courtyard")
		(35 "F.Fab" user)
		(33 "B.Fab" user)
	)
	(footprint "antmicro-footprints:C_0603_1608Metric"
		(layer "B.Cu")
		(at 186.575 152.525 180)
		(descr "Capacitor SMD 0603")
		(tags "capacitor 0603")
		(property "Reference" "C85"
			(at 29.95 10.3 0)
			(layer "B.SilkS")
			(effects
				(font
					(size 0.7 0.7)
					(thickness 0.15)
				)
				(justify left bottom mirror)
			)
		)
		(property "Value" "C_47u_0603"
			(at -1.42757 -1.770288 0)
			(layer "B.Fab")
			(effects
				(font
					(size 0.7 0.7)
					(thickness 0.15)
				)
				(justify left bottom mirror)
			)
		)
		(property "Datasheet" "https://www.murata.com/products/productdetail?partno=GRM188R60J476ME15%23"
			(at 0 0 180)
			(layer "F.Fab")
			(hide yes)
			(effects
				(font
					(size 1.27 1.27)
					(thickness 0.15)
				)
			)
		)
		(property "Manufacturer" "Murata"
			(at 0 0 180)
			(unlocked yes)
			(layer "B.Fab")
			(hide yes)
			(effects
				(font
					(size 1 1)
					(thickness 0.15)
				)
				(justify mirror)
			)
		)
		(property "MPN" "GRM188R60J476ME15D"
			(at 0 0 180)
			(unlocked yes)
			(layer "B.Fab")
			(hide yes)
			(effects
				(font
					(size 1 1)
					(thickness 0.15)
				)
				(justify mirror)
			)
		)
		(property "Val" "47u"
			(at 0 0 180)
			(unlocked yes)
			(layer "B.Fab")
			(hide yes)
			(effects
				(font
					(size 1 1)
					(thickness 0.15)
				)
				(justify mirror)
			)
		)
		(property "License" "Apache-2.0"
			(at 0 0 180)
			(unlocked yes)
			(layer "B.Fab")
			(hide yes)
			(effects
				(font
					(size 1 1)
					(thickness 0.15)
				)
				(justify mirror)
			)
		)
		(property "Author" "Antmicro"
			(at 0 0 180)
			(unlocked yes)
			(layer "B.Fab")
			(hide yes)
			(effects
				(font
					(size 1 1)
					(thickness 0.15)
				)
				(justify mirror)
			)
		)
		(property "Voltage" ""
			(at 0 0 180)
			(unlocked yes)
			(layer "B.Fab")
			(hide yes)
			(effects
				(font
					(size 1 1)
					(thickness 0.15)
				)
				(justify mirror)
			)
		)
		(property "Dielectric" ""
			(at 0 0 180)
			(unlocked yes)
			(layer "B.Fab")
			(hide yes)
			(effects
				(font
					(size 1 1)
					(thickness 0.15)
				)
				(justify mirror)
			)
		)
		(sheetname "/FPGA power/")
		(sheetfile "fpga-power.kicad_sch")
		(attr smd)
		(fp_line
			(start -0.15 0.4)
			(end 0.15 0.4)
			(stroke
				(width 0.15)
				(type solid)
			)
			(layer "B.SilkS")
		)
		(fp_line
			(start -0.15 -0.4)
			(end 0.15 -0.4)
			(stroke
				(width 0.15)
				(type solid)
			)
			(layer "B.SilkS")
		)
		(fp_rect
			(start -1.25 0.65)
			(end 1.25 -0.65)
			(stroke
				(width 0.05)
				(type solid)
			)
			(fill no)
			(layer "B.CrtYd")
		)
		(fp_rect
			(start -0.8 0.4)
			(end 0.8 -0.4)
			(stroke
				(width 0.15)
				(type solid)
			)
			(fill no)
			(layer "B.Fab")
		)
		(fp_text user "License: Apache-2.0"
			(at -1.682 -5.895 0)
			(layer "B.Fab")
			(effects
				(font
					(size 0.7 0.7)
					(thickness 0.15)
				)
				(justify left bottom mirror)
			)
		)
		(fp_text user "${REFERENCE}"
			(at -1.682 -3.895 0)
			(layer "B.Fab")
			(effects
				(font
					(size 0.7 0.7)
					(thickness 0.15)
				)
				(justify left bottom mirror)
			)
		)
		(fp_text user "Author: Antmicro"
			(at -1.682 -4.894 0)
			(layer "B.Fab")
			(effects
				(font
					(size 0.7 0.7)
					(thickness 0.15)
				)
				(justify left bottom mirror)
			)
		)
		(pad "1" smd roundrect
			(at -0.7 0 180)
			(size 0.8 1)
			(layers "B.Cu" "B.Mask" "B.Paste")
			(roundrect_rratio 0.2)
			(net 797 "+1V8")
			(pintype "passive")
		)
		(pad "2" smd roundrect
			(at 0.7 0 180)
			(size 0.8 1)
			(layers "B.Cu" "B.Mask" "B.Paste")
			(roundrect_rratio 0.2)
			(net 1 "GND")
			(pintype "passive")
		)
	)
	(footprint "antmicro-footprints:C_0402_1005Metric_EIA"
		(layer "B.Cu")
		(at 195 148.5 -90)
		(descr "Capacitor SMD 0402 (1005 Metric), square (rectangular) end terminal, IPC_7351 nominal, (Body size source: IPC-SM-782 page 76, https://www.pcb-3d.com/wordpress/wp-content/uploads/ipc-sm-782a_amendment_1_and_2.pdf)")
		(tags "capacitor 0402")
		(property "Reference" "C333"
			(at -12.4 30.6 90)
			(layer "B.SilkS")
			(effects
				(font
					(size 0.7 0.7)
					(thickness 0.15)
				)
				(justify left bottom mirror)
			)
		)
		(property "Value" "C_100n_0402"
			(at 0 -1.169 90)
			(layer "B.Fab")
			(effects
				(font
					(size 0.7 0.7)
					(thickness 0.15)
				)
				(justify left bottom mirror)
			)
		)
		(property "Manufacturer" "Murata"
			(at 0 0 270)
			(unlocked yes)
			(layer "B.Fab")
			(hide yes)
			(effects
				(font
					(size 1 1)
					(thickness 0.15)
				)
				(justify mirror)
			)
		)
		(property "MPN" "GRM155R61H104KE14D"
			(at 0 0 270)
			(unlocked yes)
			(layer "B.Fab")
			(hide yes)
			(effects
				(font
					(size 1 1)
					(thickness 0.15)
				)
				(justify mirror)
			)
		)
		(property "Val" "100n"
			(at 0 0 270)
			(unlocked yes)
			(layer "B.Fab")
			(hide yes)
			(effects
				(font
					(size 1 1)
					(thickness 0.15)
				)
				(justify mirror)
			)
		)
		(property "License" "Apache-2.0"
			(at 0 0 270)
			(unlocked yes)
			(layer "B.Fab")
			(hide yes)
			(effects
				(font
					(size 1 1)
					(thickness 0.15)
				)
				(justify mirror)
			)
		)
		(property "Author" "Antmicro"
			(at 0 0 270)
			(unlocked yes)
			(layer "B.Fab")
			(hide yes)
			(effects
				(font
					(size 1 1)
					(thickness 0.15)
				)
				(justify mirror)
			)
		)
		(property "Voltage" "50V"
			(at 0 0 270)
			(unlocked yes)
			(layer "B.Fab")
			(hide yes)
			(effects
				(font
					(size 1 1)
					(thickness 0.15)
				)
				(justify mirror)
			)
		)
		(property "Dielectric" "X5R"
			(at 0 0 270)
			(unlocked yes)
			(layer "B.Fab")
			(hide yes)
			(effects
				(font
					(size 1 1)
					(thickness 0.15)
				)
				(justify mirror)
			)
		)
		(sheetname "/FPGA banks HP/")
		(sheetfile "fpga-hp-banks.kicad_sch")
		(attr smd)
		(fp_rect
			(start -0.95 0.45)
			(end 0.95 -0.45)
			(stroke
				(width 0.05)
				(type default)
			)
			(fill no)
			(layer "B.CrtYd")
		)
		(fp_line
			(start -0.5 0.25)
			(end 0.498 0.25)
			(stroke
				(width 0.15)
				(type solid)
			)
			(layer "B.Fab")
		)
		(fp_line
			(start 0.498 0.25)
			(end 0.498 -0.248)
			(stroke
				(width 0.15)
				(type solid)
			)
			(layer "B.Fab")
		)
		(fp_line
			(start -0.5 -0.248)
			(end -0.5 0.25)
			(stroke
				(width 0.15)
				(type solid)
			)
			(layer "B.Fab")
		)
		(fp_line
			(start 0.498 -0.248)
			(end -0.5 -0.248)
			(stroke
				(width 0.15)
				(type solid)
			)
			(layer "B.Fab")
		)
		(fp_text user "Author: Antmicro"
			(at -0.9656 -5.569 90)
			(layer "B.Fab")
			(effects
				(font
					(size 0.7 0.7)
					(thickness 0.15)
				)
				(justify left bottom mirror)
			)
		)
		(fp_text user "${REFERENCE}"
			(at -0.9656 -3.169 90)
			(layer "B.Fab")
			(effects
				(font
					(size 0.7 0.7)
					(thickness 0.15)
				)
				(justify left bottom mirror)
			)
		)
		(fp_text user "License: Apache-2.0"
			(at -0.9656 -4.369 90)
			(layer "B.Fab")
			(effects
				(font
					(size 0.7 0.7)
					(thickness 0.15)
				)
				(justify left bottom mirror)
			)
		)
		(pad "1" smd roundrect
			(at -0.5 0 180)
			(size 0.6 0.6)
			(layers "B.Cu" "B.Mask" "B.Paste")
			(roundrect_rratio 0.25)
			(net 535 "/FPGA banks HP/VREF_64")
			(pintype "passive")
		)
		(pad "2" smd roundrect
			(at 0.498 0 270)
			(size 0.6 0.6)
			(layers "B.Cu" "B.Mask" "B.Paste")
			(roundrect_rratio 0.25)
			(net 1 "GND")
			(pintype "passive")
		)
	)
	(footprint "antmicro-footprints:I-PEX_CABLINE-VS_1x20_20455-A20E-76"
		(layer "B.Cu")
		(at 103.367 160.619 90)
		(property "Reference" "J11"
			(at -9.511 0.433 0)
			(layer "B.SilkS")
			(effects
				(font
					(size 0.7 0.7)
					(thickness 0.15)
				)
				(justify right bottom mirror)
			)
		)
		(property "Value" "I-PEX_CABLINE-VS_1x20_20455-A20E-76"
			(at 0 -3.5 90)
			(layer "B.Fab")
			(effects
				(font
					(size 0.7 0.7)
					(thickness 0.15)
				)
				(justify right bottom mirror)
			)
		)
		(property "Datasheet" "https://www.i-pex.com/sites/default/files/downloads/pdf/MANUAL_CABLINE-VS_HIM-08004-07EN.pdf"
			(at 0 0 90)
			(layer "F.Fab")
			(hide yes)
			(effects
				(font
					(size 1.27 1.27)
					(thickness 0.15)
				)
			)
		)
		(property "MPN" "20455-A20E-76"
			(at 0 0 90)
			(unlocked yes)
			(layer "B.Fab")
			(hide yes)
			(effects
				(font
					(size 1 1)
					(thickness 0.15)
				)
				(justify mirror)
			)
		)
		(property "Manufacturer" "I-PEX"
			(at 0 0 90)
			(unlocked yes)
			(layer "B.Fab")
			(hide yes)
			(effects
				(font
					(size 1 1)
					(thickness 0.15)
				)
				(justify mirror)
			)
		)
		(property "Author" "Antmicro"
			(at 0 0 90)
			(unlocked yes)
			(layer "B.Fab")
			(hide yes)
			(effects
				(font
					(size 1 1)
					(thickness 0.15)
				)
				(justify mirror)
			)
		)
		(property "License" "Apache-2.0"
			(at 0 0 90)
			(unlocked yes)
			(layer "B.Fab")
			(hide yes)
			(effects
				(font
					(size 1 1)
					(thickness 0.15)
				)
				(justify mirror)
			)
		)
		(sheetname "/HDMI + SD Card/")
		(sheetfile "hdmi-sd-card.kicad_sch")
		(attr smd)
		(fp_line
			(start 8.7 -2.2)
			(end 8.7 0.103)
			(stroke
				(width 0.15)
				(type solid)
			)
			(layer "B.SilkS")
		)
		(fp_line
			(start -8.702 -2.2)
			(end 8.7 -2.2)
			(stroke
				(width 0.15)
				(type solid)
			)
			(layer "B.SilkS")
		)
		(fp_line
			(start 8.7 0.103)
			(end 8.3 0.103)
			(stroke
				(width 0.15)
				(type solid)
			)
			(layer "B.SilkS")
		)
		(fp_line
			(start 8.3 0.103)
			(end 8.3 2.4)
			(stroke
				(width 0.15)
				(type solid)
			)
			(layer "B.SilkS")
		)
		(fp_line
			(start -8.301 0.103)
			(end -8.702 0.103)
			(stroke
				(width 0.15)
				(type solid)
			)
			(layer "B.SilkS")
		)
		(fp_line
			(start -8.702 0.103)
			(end -8.702 -2.2)
			(stroke
				(width 0.15)
				(type solid)
			)
			(layer "B.SilkS")
		)
		(fp_line
			(start 8.3 2.4)
			(end -8.301 2.4)
			(stroke
				(width 0.15)
				(type solid)
			)
			(layer "B.SilkS")
		)
		(fp_line
			(start -8.301 2.4)
			(end -8.301 0.103)
			(stroke
				(width 0.15)
				(type solid)
			)
			(layer "B.SilkS")
		)
		(fp_circle
			(center -5.1 1.8)
			(end -5.052 1.8)
			(stroke
				(width 0.15)
				(type solid)
			)
			(fill yes)
			(layer "B.SilkS")
		)
		(fp_rect
			(start -9.1 2.7)
			(end 9 -2.5)
			(stroke
				(width 0.05)
				(type solid)
			)
			(fill no)
			(layer "B.CrtYd")
		)
		(fp_line
			(start 8.7 -2.2)
			(end 8.7 0.101)
			(stroke
				(width 0.15)
				(type solid)
			)
			(layer "B.Fab")
		)
		(fp_line
			(start -8.701 -2.2)
			(end 8.7 -2.2)
			(stroke
				(width 0.15)
				(type solid)
			)
			(layer "B.Fab")
		)
		(fp_line
			(start 8.7 0.101)
			(end 8.3 0.101)
			(stroke
				(width 0.15)
				(type solid)
			)
			(layer "B.Fab")
		)
		(fp_line
			(start 8.3 0.101)
			(end 8.3 2.4)
			(stroke
				(width 0.15)
				(type solid)
			)
			(layer "B.Fab")
		)
		(fp_line
			(start -8.301 0.101)
			(end -8.701 0.101)
			(stroke
				(width 0.15)
				(type solid)
			)
			(layer "B.Fab")
		)
		(fp_line
			(start -8.701 0.101)
			(end -8.701 -2.2)
			(stroke
				(width 0.15)
				(type solid)
			)
			(layer "B.Fab")
		)
		(fp_line
			(start -8.3 1.8)
			(end -8.301 0.101)
			(stroke
				(width 0.15)
				(type solid)
			)
			(layer "B.Fab")
		)
		(fp_line
			(start 8.3 2.4)
			(end -7.7 2.4)
			(stroke
				(width 0.15)
				(type solid)
			)
			(layer "B.Fab")
		)
		(fp_line
			(start -7.7 2.4)
			(end -8.3 1.8)
			(stroke
				(width 0.15)
				(type solid)
			)
			(layer "B.Fab")
		)
		(fp_text user "${REFERENCE}"
			(at -9.625 -7.89 270)
			(layer "B.Fab")
			(effects
				(font
					(size 0.7 0.7)
					(thickness 0.15)
				)
				(justify left bottom mirror)
			)
		)
		(fp_text user "Author: Antmicro"
			(at -9.625 -9.09 270)
			(layer "B.Fab")
			(effects
				(font
					(size 0.7 0.7)
					(thickness 0.15)
				)
				(justify left bottom mirror)
			)
		)
		(fp_text user "License: Apache-2.0"
			(at -9.625 -6.69 270)
			(layer "B.Fab")
			(effects
				(font
					(size 0.7 0.7)
					(thickness 0.15)
				)
				(justify left bottom mirror)
			)
		)
		(pad "1" smd rect
			(at -4.75 1.803 90)
			(size 0.25 0.9)
			(layers "B.Cu" "B.Mask" "B.Paste")
			(net 490 "unconnected-(J11-Pad1)")
			(pinfunction "1")
			(pintype "passive+no_connect")
		)
		(pad "2" smd rect
			(at -4.25 1.803 90)
			(size 0.25 0.9)
			(layers "B.Cu" "B.Mask" "B.Paste")
			(net 604 "/HDMI + SD Card/HDMI_IN_HPD_CONN")
			(pinfunction "2")
			(pintype "passive")
		)
		(pad "3" smd rect
			(at -3.75 1.803 90)
			(size 0.25 0.9)
			(layers "B.Cu" "B.Mask" "B.Paste")
			(net 297 "/HDMI + SD Card/HDMI_IN_5V")
			(pinfunction "3")
			(pintype "passive")
		)
		(pad "4" smd rect
			(at -3.25 1.803 90)
			(size 0.25 0.9)
			(layers "B.Cu" "B.Mask" "B.Paste")
			(net 1 "GND")
			(pinfunction "4")
			(pintype "passive")
		)
		(pad "5" smd rect
			(at -2.75 1.803 90)
			(size 0.25 0.9)
			(layers "B.Cu" "B.Mask" "B.Paste")
			(net 499 "/HDMI + SD Card/HDMI_IN_5V.SCL")
			(pinfunction "5")
			(pintype "passive")
		)
		(pad "6" smd rect
			(at -2.25 1.803 90)
			(size 0.25 0.9)
			(layers "B.Cu" "B.Mask" "B.Paste")
			(net 480 "/HDMI + SD Card/HDMI_IN_5V.SDA")
			(pinfunction "6")
			(pintype "passive")
		)
		(pad "7" smd rect
			(at -1.75 1.803 90)
			(size 0.25 0.9)
			(layers "B.Cu" "B.Mask" "B.Paste")
			(net 496 "unconnected-(J11-Pad7)")
			(pinfunction "7")
			(pintype "passive+no_connect")
		)
		(pad "8" smd rect
			(at -1.25 1.803 90)
			(size 0.25 0.9)
			(layers "B.Cu" "B.Mask" "B.Paste")
			(net 504 "unconnected-(J11-Pad8)")
			(pinfunction "8")
			(pintype "passive+no_connect")
		)
		(pad "9" smd rect
			(at -0.75 1.803 90)
			(size 0.25 0.9)
			(layers "B.Cu" "B.Mask" "B.Paste")
			(net 292 "/FPGA MGT Interface/HDMI_IN.CLK_N")
			(pinfunction "9")
			(pintype "passive")
		)
		(pad "10" smd rect
			(at -0.25 1.803 90)
			(size 0.25 0.9)
			(layers "B.Cu" "B.Mask" "B.Paste")
			(net 1 "GND")
			(pinfunction "10")
			(pintype "passive")
		)
		(pad "11" smd rect
			(at 0.24 1.803 90)
			(size 0.25 0.9)
			(layers "B.Cu" "B.Mask" "B.Paste")
			(net 269 "/FPGA MGT Interface/HDMI_IN.CLK_P")
			(pinfunction "11")
			(pintype "passive")
		)
		(pad "12" smd rect
			(at 0.74 1.803 90)
			(size 0.25 0.9)
			(layers "B.Cu" "B.Mask" "B.Paste")
			(net 349 "/FPGA MGT Interface/HDMI_IN.D0_N")
			(pinfunction "12")
			(pintype "passive")
		)
		(pad "13" smd rect
			(at 1.249 1.803 90)
			(size 0.25 0.9)
			(layers "B.Cu" "B.Mask" "B.Paste")
			(net 1 "GND")
			(pinfunction "13")
			(pintype "passive")
		)
		(pad "14" smd rect
			(at 1.749 1.803 90)
			(size 0.25 0.9)
			(layers "B.Cu" "B.Mask" "B.Paste")
			(net 380 "/FPGA MGT Interface/HDMI_IN.D0_P")
			(pinfunction "14")
			(pintype "passive")
		)
		(pad "15" smd rect
			(at 2.249 1.803 90)
			(size 0.25 0.9)
			(layers "B.Cu" "B.Mask" "B.Paste")
			(net 346 "/FPGA MGT Interface/HDMI_IN.D1_N")
			(pinfunction "15")
			(pintype "passive")
		)
		(pad "16" smd rect
			(at 2.749 1.803 90)
			(size 0.25 0.9)
			(layers "B.Cu" "B.Mask" "B.Paste")
			(net 1 "GND")
			(pinfunction "16")
			(pintype "passive")
		)
		(pad "17" smd rect
			(at 3.249 1.803 90)
			(size 0.25 0.9)
			(layers "B.Cu" "B.Mask" "B.Paste")
			(net 348 "/FPGA MGT Interface/HDMI_IN.D1_P")
			(pinfunction "17")
			(pintype "passive")
		)
		(pad "18" smd rect
			(at 3.749 1.803 90)
			(size 0.25 0.9)
			(layers "B.Cu" "B.Mask" "B.Paste")
			(net 342 "/FPGA MGT Interface/HDMI_IN.D2_N")
			(pinfunction "18")
			(pintype "passive")
		)
		(pad "19" smd rect
			(at 4.248 1.803 90)
			(size 0.25 0.9)
			(layers "B.Cu" "B.Mask" "B.Paste")
			(net 1 "GND")
			(pinfunction "19")
			(pintype "passive")
		)
		(pad "20" smd rect
			(at 4.748 1.803 90)
			(size 0.25 0.9)
			(layers "B.Cu" "B.Mask" "B.Paste")
			(net 344 "/FPGA MGT Interface/HDMI_IN.D2_P")
			(pinfunction "20")
			(pintype "passive")
		)
		(pad "SH" smd rect
			(at -7.851 -1.017 90)
			(size 1.4 1.9)
			(layers "B.Cu" "B.Mask" "B.Paste")
			(net 1 "GND")
			(pinfunction "SH")
			(pintype "passive")
		)
		(pad "SH" smd rect
			(at -7.771 1.349 90)
			(size 0.7 1.27)
			(layers "B.Cu" "B.Mask" "B.Paste")
			(net 1 "GND")
			(pinfunction "SH")
			(pintype "passive")
		)
		(pad "SH" smd rect
			(at -5.651 1.803 90)
			(size 0.55 0.9)
			(layers "B.Cu" "B.Mask" "B.Paste")
			(net 1 "GND")
			(pinfunction "SH")
			(pintype "passive")
		)
		(pad "SH" smd rect
			(at 5.65 1.803 90)
			(size 0.55 0.9)
			(layers "B.Cu" "B.Mask" "B.Paste")
			(net 1 "GND")
			(pinfunction "SH")
			(pintype "passive")
		)
		(pad "SH" smd rect
			(at 7.767 1.349 90)
			(size 0.7 1.27)
			(layers "B.Cu" "B.Mask" "B.Paste")
			(net 1 "GND")
			(pinfunction "SH")
			(pintype "passive")
		)
		(pad "SH" smd rect
			(at 7.849 -1.017 90)
			(size 1.4 1.9)
			(layers "B.Cu" "B.Mask" "B.Paste")
			(net 1 "GND")
			(pinfunction "SH")
			(pintype "passive")
		)
	)
)
